;LEADER: 12 
;HEADER: 
;CODE  : ASCII 
;FILE  : 9332_F0TG_MB_C_V02_0417_0820-bd-18-8.drl for backdrilling ... from layer BOTTOM to layer GND3
;DESIGN: 9332_F0TG_MB_C_V02_0417_0820.brd
;MUST-NOT-CUT-LAYER = IN3,  MAX_DRILL_DEPTH = 61.70 MILS,  MFG_STUB_LENGTH = 0.00 MILS
;   BackdrillSize 1. = 14.800000 Tolerance = +0.000000/-0.000000 NON_PLATED MILS Quantity = 968
;   BackdrillSize 2. = 17.000000 Tolerance = +0.000000/-0.000000 NON_PLATED MILS Quantity = 716
%
G90
X0496422Y1533336
X0491698Y1533336
X0486973Y1533336
R02X-0004724
X0472800Y1533336
X0468076Y1533336
X0463351Y1533336
X0458627Y1533336
X0524769Y1533336
X0520044Y1533336
X0515320Y1533336
X0510595Y1533336
X0505871Y1533336
X0501147Y1533336
X0453903Y1533336
X0494847Y1530608
R02X-0004724
X0480674Y1530608
X0475950Y1530608
X0471225Y1530608
R02X-0004724
X0457052Y1530608
X0523194Y1530608
X0518470Y1530608
X0513745Y1530608
X0509021Y1530608
X0504296Y1530608
X0499572Y1530608
X0452328Y1530608
X0232249Y1533336
X0227525Y1533336
X0222800Y1533336
R02X-0004724
X0208627Y1533336
X0203903Y1533336
X0199178Y1533336
X0194454Y1533336
X0260596Y1533336
X0255871Y1533336
X0251147Y1533336
X0246422Y1533336
X0241698Y1533336
X0236974Y1533336
X0189730Y1533336
X0230674Y1530608
R02X-0004724
X0216501Y1530608
X0211777Y1530608
X0207052Y1530608
R02X-0004724
X0192879Y1530608
X0259021Y1530608
X0254297Y1530608
X0249572Y1530608
X0244848Y1530608
X0240123Y1530608
X0235399Y1530608
X0188155Y1530608
X1504296Y1566336
X1499572Y1566336
X1494847Y1566336
R02X-0004724
X1480674Y1566336
X1475950Y1566336
X1471225Y1566336
X1466501Y1566336
X1532643Y1566336
X1527918Y1566336
X1523194Y1566336
X1518469Y1566336
X1513745Y1566336
X1509021Y1566336
X1461777Y1566336
X1502721Y1563608
R02X-0004724
X1488548Y1563608
X1483824Y1563608
X1479099Y1563608
R02X-0004724
X1464926Y1563608
X1531068Y1563608
X1526344Y1563608
X1521619Y1563608
X1516895Y1563608
X1512170Y1563608
X1507446Y1563608
X1460202Y1563608
X1368184Y1566336
X1363460Y1566336
X1358735Y1566336
R02X-0004724
X1344562Y1566336
X1339838Y1566336
X1335113Y1566336
X1330389Y1566336
X1396531Y1566336
X1391806Y1566336
X1387082Y1566336
X1382357Y1566336
X1377633Y1566336
X1372909Y1566336
X1325665Y1566336
X1366609Y1563608
R02X-0004724
X1352436Y1563608
X1347712Y1563608
X1342987Y1563608
R02X-0004724
X1328814Y1563608
X1394956Y1563608
X1390232Y1563608
X1385507Y1563608
X1380783Y1563608
X1376058Y1563608
X1371334Y1563608
X1324090Y1563608
X0624484Y1519698
X0485649Y1107781
X0619760Y1519698
X0474546Y1120537
X0615035Y1519698
X0474546Y1126915
X0610311Y1519698
X0474546Y1114159
X0605587Y1519698
X0463444Y1120537
X0600862Y1519698
X0463444Y1126915
X0596138Y1519698
X0463444Y1114159
X0591413Y1519698
X0454192Y1123726
X0586689Y1519698
X0454192Y1117348
X0652831Y1519698
X0496751Y1114159
X0648106Y1519698
X0496751Y1120537
X0643382Y1519698
X0496751Y1107781
X0638657Y1519698
X0485649Y1114159
X0633933Y1519698
X0485649Y1120537
X0629209Y1519698
X0485649Y1126915
X0581965Y1519698
X0454192Y1110970
X0622909Y1516970
X0481948Y1107781
X0618185Y1516970
X0470845Y1120537
X0613461Y1516970
X0470845Y1126915
X0608736Y1516970
X0470845Y1114159
X0604012Y1516970
X0459743Y1120537
X0599287Y1516970
X0459743Y1126915
X0594563Y1516970
X0459743Y1114159
X0589839Y1516970
X0450491Y1123726
X0585114Y1516970
X0450491Y1117348
X0651256Y1516970
X0493050Y1114159
X0646532Y1516970
X0493050Y1120537
X0641807Y1516970
X0493050Y1107781
X0637083Y1516970
X0481948Y1114159
X0632358Y1516970
X0481948Y1120537
X0627634Y1516970
X0481948Y1126915
X0580390Y1516970
X0450491Y1110970
X0407957Y1114159
X0407957Y1126915
X0407957Y1120537
X0396855Y1107781
X0396855Y1126915
X0396855Y1120537
X0396855Y1114159
X0385752Y1107781
X0385752Y1120537
X0428311Y1110970
R02Y0006378
X0419059Y1114159
X0419059Y1126915
X0419059Y1120537
X0385752Y1114159
X0411658Y1114159
X0411658Y1126915
X0411658Y1120537
X0400555Y1107781
X0400555Y1126915
X0400555Y1120537
X0400555Y1114159
X0389453Y1107781
X0389453Y1120537
X0432012Y1110970
R02Y0006378
X0422760Y1114159
X0422760Y1126915
X0422760Y1120537
X0389453Y1114159
X1632358Y1552698
X1461791Y1107780
X1627634Y1552698
X1450688Y1120536
X1622909Y1552698
X1450688Y1126914
X1618185Y1552698
X1450688Y1114158
X1613461Y1552698
X1439586Y1120536
X1608736Y1552698
X1439586Y1126914
X1604012Y1552698
X1439586Y1114158
X1599287Y1552698
X1430334Y1123725
X1594563Y1552698
X1430334Y1117347
X1660705Y1552698
X1472893Y1114158
X1655980Y1552698
X1472893Y1120536
X1651256Y1552698
X1472893Y1107780
X1646531Y1552698
X1461791Y1114158
X1641807Y1552698
X1461791Y1120536
X1637083Y1552698
X1461791Y1126914
X1589839Y1552698
X1430334Y1110969
X1630783Y1549970
X1458090Y1107780
X1626059Y1549970
X1446987Y1120536
X1621335Y1549970
X1446987Y1126914
X1616610Y1549970
X1446987Y1114158
X1611886Y1549970
X1435885Y1120536
X1607161Y1549970
X1435885Y1126914
X1602437Y1549970
X1435885Y1114158
X1597713Y1549970
X1426633Y1123725
X1592988Y1549970
X1426633Y1117347
X1659130Y1549970
X1469192Y1114158
X1654406Y1549970
X1469192Y1120536
X1649681Y1549970
X1469192Y1107780
X1644957Y1549970
X1458090Y1114158
X1640232Y1549970
X1458090Y1120536
X1635508Y1549970
X1458090Y1126914
X1588264Y1549970
X1426633Y1110969
X1384099Y1114158
X1384099Y1126914
X1384099Y1120536
X1372997Y1107780
X1372997Y1126914
X1372997Y1120536
X1372997Y1114158
X1361894Y1107780
X1361894Y1120536
X1404453Y1110969
R02Y0006378
X1395201Y1114158
X1395201Y1126914
X1395201Y1120536
X1361894Y1114158
X1387800Y1114158
X1387800Y1126914
X1387800Y1120536
X1376697Y1107780
X1376697Y1126914
X1376697Y1120536
X1376697Y1114158
X1365595Y1107780
X1365595Y1120536
X1408154Y1110969
R02Y0006378
X1398902Y1114158
X1398902Y1126914
X1398902Y1120536
X1365595Y1114158
X0561515Y1053568
X0555964Y1044001
X0561515Y1066324
X0557814Y1149237
X0557814Y1130103
X0557814Y1110970
R02Y-0019134
X0561515Y1142859
X0561515Y1123726
X0561515Y1104592
X0561515Y1085458
X0563365Y1069513
X0555964Y1146048
X0555964Y1126915
X0555964Y1107781
R02Y-0019134
X0563365Y1146048
X0563365Y1126915
X0563365Y1107781
X0563365Y1088647
X0555964Y1101403
X0561515Y1098214
X0557814Y1098214
X0563365Y1095025
X0555964Y1095025
X0561515Y1091836
X0557814Y1085458
X0557814Y1155615
X0563365Y1152426
X0563365Y1082269
X0555964Y1152426
X0561515Y1149237
X0557814Y1142859
X0563365Y1139670
X0555964Y1139670
X0561515Y1136481
X0557814Y1136481
X0563365Y1133293
X0555964Y1133293
X0561515Y1130103
X0555964Y1082269
X0557814Y1123726
X0563365Y1120537
X0555964Y1120537
X0561515Y1117348
X0557814Y1117348
X0563365Y1114159
X0555964Y1114159
X0561515Y1110970
X0557814Y1104592
X0563365Y1101403
X0561515Y1079080
X0563365Y1050379
X0557814Y1047190
X0557814Y1066324
X0563365Y1063135
X0555964Y1063135
X0561515Y1059946
X0557814Y1079080
X0563365Y1075891
X0555964Y1075891
X0561515Y1072702
X0561515Y1040812
X0557814Y1040812
X0555964Y1037623
X0563365Y1037623
X0561515Y1034434
X0557814Y1034434
X0555964Y1031245
X0555964Y1050379
X0554783Y1007183
X0554783Y0975293
X0554783Y0956159
R02Y-0019134
X0554783Y0898758
X0562184Y0968915
R03Y-0019134
X0562184Y0892380
X0556633Y0972104
R03Y-0019134
X0556633Y0895569
X0560334Y0972104
R03Y-0019134
X0560334Y0895569
X0556633Y0908325
X0562184Y0905135
X0554783Y0905135
X0560334Y0901947
X0556633Y0901947
X0562184Y0898758
X0554783Y0892380
X0554783Y0962537
X0560334Y0959348
X0560334Y0889191
X0556633Y0959348
X0562184Y0956159
X0554783Y0949781
X0560334Y0946592
X0556633Y0946592
X0562184Y0943403
X0554783Y0943403
X0560334Y0940214
X0556633Y0940214
X0562184Y0937025
X0556633Y0889191
X0554783Y0930647
X0560334Y0927458
X0556633Y0927458
X0562184Y0924269
X0554783Y0924269
X0560334Y0921080
X0556633Y0921080
X0562184Y0917891
X0554783Y0911513
X0560334Y0908325
X0562184Y0886002
X0556633Y0991238
X0562184Y0988049
X0554783Y0981671
X0560334Y0978482
X0556633Y0978482
X0562184Y0975293
X0554783Y0968915
X0560334Y0965726
X0556633Y0965726
X0562184Y0962537
X0556633Y1003994
X0560334Y1003994
X0562184Y1000805
X0554783Y1000805
X0556633Y0997616
X0560334Y0997616
X0562184Y0994427
X0554783Y0988049
X0562184Y1007183
X0560334Y1010372
X0556633Y0984860
X1537657Y1053567
X1532106Y1044000
X1537657Y1066323
X1533956Y1149236
X1533956Y1130102
X1533956Y1110969
R02Y-0019134
X1537657Y1142858
X1537657Y1123725
X1537657Y1104591
X1537657Y1085457
X1539507Y1069512
X1532106Y1146047
X1532106Y1126914
X1532106Y1107780
R02Y-0019134
X1539507Y1146047
X1539507Y1126914
X1539507Y1107780
X1539507Y1088646
X1532106Y1101402
X1537657Y1098213
X1533956Y1098213
X1539507Y1095024
X1532106Y1095024
X1537657Y1091835
X1533956Y1085457
X1533956Y1155614
X1539507Y1152425
X1539507Y1082268
X1532106Y1152425
X1537657Y1149236
X1533956Y1142858
X1539507Y1139669
X1532106Y1139669
X1537657Y1136480
X1533956Y1136480
X1539507Y1133292
X1532106Y1133292
X1537657Y1130102
X1532106Y1082268
X1533956Y1123725
X1539507Y1120536
X1532106Y1120536
X1537657Y1117347
X1533956Y1117347
X1539507Y1114158
X1532106Y1114158
X1537657Y1110969
X1533956Y1104591
X1539507Y1101402
X1537657Y1079079
X1539507Y1050378
X1533956Y1047189
X1533956Y1066323
X1539507Y1063134
X1532106Y1063134
X1537657Y1059945
X1533956Y1079079
X1539507Y1075890
X1532106Y1075890
X1537657Y1072701
X1537657Y1040811
X1533956Y1040811
X1532106Y1037622
X1539507Y1037622
X1537657Y1034433
X1533956Y1034433
X1532106Y1031244
X1532106Y1050378
X1530925Y1007182
X1530925Y0975292
X1530925Y0956158
R02Y-0019134
X1530925Y0898757
X1538326Y0968914
R03Y-0019134
X1538326Y0892379
X1532775Y0972103
R03Y-0019134
X1532775Y0895568
X1536476Y0972103
R03Y-0019134
X1536476Y0895568
X1532775Y0908324
X1538326Y0905134
X1530925Y0905134
X1536476Y0901946
X1532775Y0901946
X1538326Y0898757
X1530925Y0892379
X1530925Y0962536
X1536476Y0959347
X1536476Y0889190
X1532775Y0959347
X1538326Y0956158
X1530925Y0949780
X1536476Y0946591
X1532775Y0946591
X1538326Y0943402
X1530925Y0943402
X1536476Y0940213
X1532775Y0940213
X1538326Y0937024
X1532775Y0889190
X1530925Y0930646
X1536476Y0927457
X1532775Y0927457
X1538326Y0924268
X1530925Y0924268
X1536476Y0921079
X1532775Y0921079
X1538326Y0917890
X1530925Y0911512
X1536476Y0908324
X1538326Y0886001
X1532775Y0991237
X1538326Y0988048
X1530925Y0981670
X1536476Y0978481
X1532775Y0978481
X1538326Y0975292
X1530925Y0968914
X1536476Y0965725
X1532775Y0965725
X1538326Y0962536
X1532775Y1003993
X1536476Y1003993
X1538326Y1000804
X1530925Y1000804
X1532775Y0997615
X1536476Y0997615
X1538326Y0994426
X1530925Y0988048
X1538326Y1007182
X1536476Y1010371
X1532775Y0984859
X0320988Y1053568
X0319138Y1044001
X0320988Y1066324
X0324689Y1149237
X0324689Y1130103
X0324689Y1110970
R02Y-0019134
X0320988Y1142859
X0320988Y1123726
X0320988Y1104592
X0320988Y1085458
X0319138Y1069513
X0326539Y1146048
X0326539Y1126915
X0326539Y1107781
R02Y-0019134
X0319138Y1146048
X0319138Y1126915
X0319138Y1107781
X0319138Y1088647
X0326539Y1101403
X0320988Y1098214
X0324689Y1098214
X0319138Y1095025
X0326539Y1095025
X0320988Y1091836
X0324689Y1085458
X0324689Y1155615
X0319138Y1152426
X0319138Y1082269
X0326539Y1152426
X0320988Y1149237
X0324689Y1142859
X0319138Y1139670
X0326539Y1139670
X0320988Y1136481
X0324689Y1136481
X0319138Y1133293
X0326539Y1133293
X0320988Y1130103
X0326539Y1082269
X0324689Y1123726
X0319138Y1120537
X0326539Y1120537
X0320988Y1117348
X0324689Y1117348
X0319138Y1114159
X0326539Y1114159
X0320988Y1110970
X0324689Y1104592
X0319138Y1101403
X0320988Y1079080
X0319138Y1050379
X0324689Y1047190
X0324689Y1066324
X0319138Y1063135
X0326539Y1063135
X0320988Y1059946
X0324689Y1079080
X0319138Y1075891
X0326539Y1075891
X0320988Y1072702
X0320988Y1040812
X0324689Y1040812
X0326539Y1037623
X0319138Y1037623
X0320988Y1034434
X0324689Y1034434
X0326539Y1031245
X0326539Y1050379
X0325358Y1007183
X0325358Y0975293
X0325358Y0956159
R02Y-0019134
X0325358Y0898758
X0317957Y0968915
R03Y-0019134
X0317957Y0892380
X0323508Y0972104
R03Y-0019134
X0323508Y0895569
X0319807Y0972104
R03Y-0019134
X0319807Y0895569
X0323508Y0908325
X0317957Y0905135
X0325358Y0905135
X0319807Y0901947
X0323508Y0901947
X0317957Y0898758
X0325358Y0892380
X0325358Y0962537
X0319807Y0959348
X0319807Y0889191
X0323508Y0959348
X0317957Y0956159
X0325358Y0949781
X0319807Y0946592
X0323508Y0946592
X0317957Y0943403
X0325358Y0943403
X0319807Y0940214
X0323508Y0940214
X0317957Y0937025
X0323508Y0889191
X0325358Y0930647
X0319807Y0927458
X0323508Y0927458
X0317957Y0924269
X0325358Y0924269
X0319807Y0921080
X0323508Y0921080
X0317957Y0917891
X0325358Y0911513
X0319807Y0908325
X0317957Y0886002
X0325358Y0994427
X0319807Y0991238
X0325358Y0981671
X0319807Y0978482
X0323508Y0978482
X0317957Y0975293
X0325358Y0968915
X0319807Y0965726
X0323508Y0965726
X0317957Y0962537
X0323508Y1003994
X0319807Y1003994
X0317957Y1000805
X0325358Y1000805
X0323508Y0997616
X0319807Y0997616
X0317957Y0994427
X0325358Y0988049
X0317957Y1007183
X0319807Y1010372
X0323508Y0984860
X1297130Y1053567
X1295280Y1044000
X1297130Y1066323
X1300831Y1149236
X1300831Y1130102
X1300831Y1110969
R02Y-0019134
X1297130Y1142858
X1297130Y1123725
X1297130Y1104591
X1297130Y1085457
X1295280Y1069512
X1302681Y1146047
X1302681Y1126914
X1302681Y1107780
R02Y-0019134
X1295280Y1146047
X1295280Y1126914
X1295280Y1107780
X1295280Y1088646
X1302681Y1101402
X1297130Y1098213
X1300831Y1098213
X1295280Y1095024
X1302681Y1095024
X1297130Y1091835
X1300831Y1085457
X1300831Y1155614
X1295280Y1152425
X1295280Y1082268
X1302681Y1152425
X1297130Y1149236
X1300831Y1142858
X1295280Y1139669
X1302681Y1139669
X1297130Y1136480
X1300831Y1136480
X1295280Y1133292
X1302681Y1133292
X1297130Y1130102
X1302681Y1082268
X1300831Y1123725
X1295280Y1120536
X1302681Y1120536
X1297130Y1117347
X1300831Y1117347
X1295280Y1114158
X1302681Y1114158
X1297130Y1110969
X1300831Y1104591
X1295280Y1101402
X1297130Y1079079
X1295280Y1050378
X1300831Y1047189
X1300831Y1066323
X1295280Y1063134
X1302681Y1063134
X1297130Y1059945
X1300831Y1079079
X1295280Y1075890
X1302681Y1075890
X1297130Y1072701
X1297130Y1040811
X1300831Y1040811
X1302681Y1037622
X1295280Y1037622
X1297130Y1034433
X1300831Y1034433
X1302681Y1031244
X1302681Y1050378
X1301500Y1007182
X1301500Y0975292
X1301500Y0956158
R02Y-0019134
X1301500Y0898757
X1294099Y0968914
R03Y-0019134
X1294099Y0892379
X1299650Y0972103
R03Y-0019134
X1299650Y0895568
X1295949Y0972103
R03Y-0019134
X1295949Y0895568
X1299650Y0908324
X1294099Y0905134
X1301500Y0905134
X1295949Y0901946
X1299650Y0901946
X1294099Y0898757
X1301500Y0892379
X1301500Y0962536
X1295949Y0959347
X1295949Y0889190
X1299650Y0959347
X1294099Y0956158
X1301500Y0949780
X1295949Y0946591
X1299650Y0946591
X1294099Y0943402
X1301500Y0943402
X1295949Y0940213
X1299650Y0940213
X1294099Y0937024
X1299650Y0889190
X1301500Y0930646
X1295949Y0927457
X1299650Y0927457
X1294099Y0924268
X1301500Y0924268
X1295949Y0921079
X1299650Y0921079
X1294099Y0917890
X1301500Y0911512
X1295949Y0908324
X1294099Y0886001
X1301500Y0994426
X1295949Y0991237
X1301500Y0981670
X1295949Y0978481
X1299650Y0978481
X1294099Y0975292
X1301500Y0968914
X1295949Y0965725
X1299650Y0965725
X1294099Y0962536
X1299650Y1003993
X1295949Y1003993
X1294099Y1000804
X1301500Y1000804
X1299650Y0997615
X1295949Y0997615
X1294099Y0994426
X1301500Y0988048
X1294099Y1007182
X1295949Y1010371
X1299650Y0984859
X0421579Y0949781
X1434704Y0949780
X0410477Y0956159
X1445806Y0956158
X0410477Y0943403
X1445806Y0943402
X0410477Y0949781
X1445806Y0949780
X0399374Y0956159
X1456909Y0956158
X0399374Y0943403
X1456909Y0943402
X0399374Y0949781
X1456909Y0949780
X0388272Y0956159
X1468011Y0956158
X0388272Y0943403
X1468011Y0943402
X0430831Y0952970
X1425452Y0952969
X0430831Y0946592
X1425452Y0946591
X0430831Y0940214
X1425452Y0940213
X0421579Y0956159
X1434704Y0956158
X0421579Y0937025
X1434704Y0937024
X0421579Y0943403
X1434704Y0943402
X0388272Y0949781
X1468011Y0949780
X0417878Y0949781
X1438405Y0949780
X0406776Y0956159
X1449507Y0956158
X0406776Y0943403
X1449507Y0943402
X0406776Y0949781
X1449507Y0949780
X0395673Y0956159
X1460609Y0956158
X0395673Y0943403
X1460609Y0943402
X0395673Y0949781
X1460609Y0949780
X0384571Y0956159
X1471712Y0956158
X0384571Y0943403
X1471712Y0943402
X0427130Y0952970
X1429153Y0952969
X0427130Y0946592
X1429153Y0946591
X0427130Y0940214
X1429153Y0940213
X0417878Y0956159
X1438405Y0956158
X0417878Y0937025
X1438405Y0937024
X0417878Y0943403
X1438405Y0943402
X0384571Y0949781
X1471712Y0949780
M00
X0300106Y1592380
R08X-0012060
X0372466Y1592380
R05X-0012060
X0191566Y1592380
X0296706Y1592380
X0284646Y1592380
R07X-0012060
X0369066Y1592380
R05X-0012060
X0188166Y1592380
X0559069Y0101985
X0400426Y0116215
X0559069Y0105385
X0400426Y0112815
X0405606Y0129715
X0514240Y0097146
X0405606Y0125815
X0517640Y0097146
X0526460Y0097495
X0445014Y0094684
X0526460Y0100895
X0448414Y0094684
X1436263Y-0001711
X1245840Y-0001711
X1436263Y0001689
X1245840Y0001689
X1177404Y-0018311
X0842320Y-0018311
X1177404Y-0021711
X0842320Y-0021711
X0385001Y0813527
X0372000Y0843027
X0385001Y0816927
X0372000Y0846427
X0371999Y0822927
X0372000Y0835197
X0371999Y0819527
X0372000Y0831797
X0716699Y0209021
X0716699Y0197187
X0716699Y0185687
X0716699Y0173687
X0716699Y0212421
X0716699Y0200587
X0716699Y0189087
X0716699Y0177087
X0229651Y1452895
X0222951Y1462595
X0216251Y1472295
X0202851Y1452895
X0196151Y1462595
X0189451Y1472295
X0176051Y1452895
X0169351Y1462595
X0163113Y1480190
X0280621Y1494082
X0280621Y1480682
X0273251Y1452895
X0256451Y1452895
X0249751Y1462595
X0243051Y1472295
X0163113Y1505390
X0233051Y1452895
X0226351Y1462595
X0219651Y1472295
X0206251Y1452895
X0199551Y1462595
X0192851Y1472295
X0179451Y1452895
X0172751Y1462595
X0163113Y1483590
X0280621Y1497482
X0280621Y1484082
X0269851Y1452895
X0259851Y1452895
X0253151Y1462595
X0246451Y1472295
X0163113Y1501990
X1237524Y1485895
X1230824Y1495595
X1224124Y1505295
X1210724Y1485895
X1204024Y1495595
X1197324Y1505295
X1183924Y1485895
X1177224Y1495595
X1170986Y1513190
X1288494Y1527082
X1288494Y1513682
X1281124Y1485895
X1264324Y1485895
X1257624Y1495595
X1250924Y1505295
X1170986Y1538390
X1240924Y1485895
X1234224Y1495595
X1227524Y1505295
X1214124Y1485895
X1207424Y1495595
X1200724Y1505295
X1187324Y1485895
X1180624Y1495595
X1170986Y1516590
X1288494Y1530482
X1288494Y1517082
X1277724Y1485895
X1267724Y1485895
X1261024Y1495595
X1254324Y1505295
X1170986Y1534990
X0782300Y1064706
X0766158Y1051320
X0782300Y1084785
X0766158Y1238722
R04Y-0036811
X0782300Y1232029
R03Y-0036811
X0782300Y1088131
X0766158Y1235375
R04Y-0036811
X0782300Y1235375
R03Y-0036811
X0782300Y1151714
X0782300Y1145021
X0766158Y1141675
X0766158Y1134982
X0782300Y1138328
X0782300Y1131635
X0766158Y1118249
X0766158Y1252108
X0766158Y1245415
X0766158Y1111556
X0782300Y1248761
X0782300Y1242068
X0766158Y1228682
X0766158Y1221989
X0782300Y1225336
X0782300Y1218643
X0766158Y1215297
X0766158Y1208604
X0782300Y1211950
X0782300Y1205257
X0782300Y1114903
X0766158Y1191871
X0766158Y1185178
X0782300Y1188525
X0782300Y1181832
X0766158Y1178486
X0766158Y1171793
X0782300Y1175139
X0782300Y1168446
X0766158Y1155060
X0766158Y1148367
X0782300Y1108210
X0766158Y1058013
X0782300Y1054667
X0766158Y1081438
X0766158Y1074745
X0782300Y1078092
X0782300Y1071399
X0766158Y1104863
X0766158Y1098171
X0782300Y1101517
X0782300Y1094824
X0782300Y1047974
X0766158Y1044627
X0782300Y1041281
X0766158Y1037934
X0782300Y1034588
X0766158Y1031241
X0782300Y1027895
X0782300Y1061360
X0782300Y1001123
X0766158Y0944234
X0766158Y0907423
X0766158Y0870611
R02Y-0036811
X0782300Y0937541
R04Y-0036811
X0766158Y0940887
R04Y-0036811
X0782300Y0940887
R04Y-0036811
X0782300Y0820415
X0782300Y0813722
X0766158Y0810375
X0766158Y0803682
X0782300Y0807029
X0782300Y0800336
X0766158Y0786950
X0766158Y0920808
X0766158Y0914115
X0766158Y0780257
X0782300Y0917462
X0782300Y0910769
X0766158Y0897383
X0766158Y0890690
X0782300Y0894037
X0782300Y0887344
X0766158Y0883997
X0766158Y0877304
X0782300Y0880651
X0782300Y0873958
X0782300Y0783604
X0766158Y0860572
X0766158Y0853879
X0782300Y0857226
X0782300Y0850533
X0766158Y0847186
X0766158Y0840493
X0782300Y0843840
X0782300Y0837147
X0766158Y0823761
X0766158Y0817068
X0782300Y0776911
X0766158Y0971005
X0782300Y0967659
X0766158Y0957619
X0766158Y0950926
X0782300Y0954273
X0782300Y0947580
X0766158Y0934194
X0766158Y0927501
X0782300Y0930848
X0782300Y0924155
X0782300Y0994430
X0766158Y0991084
X0782300Y0987737
X0766158Y0984391
X0782300Y0981045
X0766158Y0977698
X0782300Y0974352
X0766158Y0964312
X0766158Y0997777
X0766158Y1001123
X1758442Y1064705
X1742300Y1051319
X1758442Y1084784
X1742300Y1238721
R04Y-0036811
X1758442Y1232028
R03Y-0036811
X1758442Y1088130
X1742300Y1235374
R04Y-0036811
X1758442Y1235374
R03Y-0036811
X1758442Y1151713
X1758442Y1145020
X1742300Y1141674
X1742300Y1134981
X1758442Y1138327
X1758442Y1131634
X1742300Y1118248
X1742300Y1252107
X1742300Y1245414
X1742300Y1111555
X1758442Y1248760
X1758442Y1242067
X1742300Y1228681
X1742300Y1221988
X1758442Y1225335
X1758442Y1218642
X1742300Y1215296
X1742300Y1208603
X1758442Y1211949
X1758442Y1205256
X1758442Y1114902
X1742300Y1191870
X1742300Y1185177
X1758442Y1188524
X1758442Y1181831
X1742300Y1178485
X1742300Y1171792
X1758442Y1175138
X1758442Y1168445
X1742300Y1155059
X1742300Y1148366
X1758442Y1108209
X1742300Y1058012
X1758442Y1054666
X1742300Y1081437
X1742300Y1074744
X1758442Y1078091
X1758442Y1071398
X1742300Y1104862
X1742300Y1098170
X1758442Y1101516
X1758442Y1094823
X1758442Y1047973
X1742300Y1044626
X1758442Y1041280
X1742300Y1037933
X1758442Y1034587
X1742300Y1031240
X1758442Y1027894
X1758442Y1061359
X1758442Y1001122
X1742300Y0944233
X1742300Y0907422
X1742300Y0870610
R02Y-0036811
X1758442Y0937540
R04Y-0036811
X1742300Y0940886
R04Y-0036811
X1758442Y0940886
R04Y-0036811
X1758442Y0820414
X1758442Y0813721
X1742300Y0810374
X1742300Y0803681
X1758442Y0807028
X1758442Y0800335
X1742300Y0786949
X1742300Y0920807
X1742300Y0914114
X1742300Y0780256
X1758442Y0917461
X1758442Y0910768
X1742300Y0897382
X1742300Y0890689
X1758442Y0894036
X1758442Y0887343
X1742300Y0883996
X1742300Y0877303
X1758442Y0880650
X1758442Y0873957
X1758442Y0783603
X1742300Y0860571
X1742300Y0853878
X1758442Y0857225
X1758442Y0850532
X1742300Y0847185
X1742300Y0840492
X1758442Y0843839
X1758442Y0837146
X1742300Y0823760
X1742300Y0817067
X1758442Y0776910
X1742300Y0971004
X1758442Y0967658
X1742300Y0957618
X1742300Y0950925
X1758442Y0954272
X1758442Y0947579
X1742300Y0934193
X1742300Y0927500
X1758442Y0930847
X1758442Y0924154
X1758442Y0994429
X1742300Y0991083
X1758442Y0987736
X1742300Y0984390
X1758442Y0981044
X1742300Y0977697
X1758442Y0974351
X1742300Y0964311
X1742300Y0997776
X1742300Y1001122
X0115166Y1064706
X0099024Y1051320
X0115166Y1084785
X0099024Y1238722
R04Y-0036811
X0115166Y1232029
R03Y-0036811
X0115166Y1088131
X0099024Y1235375
R04Y-0036811
X0115166Y1235375
R03Y-0036811
X0115166Y1151714
X0115166Y1145021
X0099024Y1141675
X0099024Y1134982
X0115166Y1138328
X0115166Y1131635
X0099024Y1118249
X0099024Y1252108
X0099024Y1245415
X0099024Y1111556
X0115166Y1248761
X0115166Y1242068
X0099024Y1228682
X0099024Y1221989
X0115166Y1225336
X0115166Y1218643
X0099024Y1215297
X0099024Y1208604
X0115166Y1211950
X0115166Y1205257
X0115166Y1114903
X0099024Y1191871
X0099024Y1185178
X0115166Y1188525
X0115166Y1181832
X0099024Y1178486
X0099024Y1171793
X0115166Y1175139
X0115166Y1168446
X0099024Y1155060
X0099024Y1148367
X0115166Y1108210
X0099024Y1058013
X0115166Y1054667
X0099024Y1081438
X0099024Y1074745
X0115166Y1078092
X0115166Y1071399
X0099024Y1104863
X0099024Y1098171
X0115166Y1101517
X0115166Y1094824
X0115166Y1047974
X0099024Y1044627
X0115166Y1041281
X0099024Y1037934
X0115166Y1034588
X0099024Y1031241
X0115166Y1027895
X0115166Y1061360
X0115166Y1001123
X0099024Y0944234
X0099024Y0907423
X0099024Y0870611
R02Y-0036811
X0115166Y0937541
R04Y-0036811
X0099024Y0940887
R04Y-0036811
X0115166Y0940887
R04Y-0036811
X0115166Y0820415
X0115166Y0813722
X0099024Y0810375
X0099024Y0803682
X0115166Y0807029
X0115166Y0800336
X0099024Y0786950
X0099024Y0920808
X0099024Y0914115
X0099024Y0780257
X0115166Y0917462
X0115166Y0910769
X0099024Y0897383
X0099024Y0890690
X0115166Y0894037
X0115166Y0887344
X0099024Y0883997
X0099024Y0877304
X0115166Y0880651
X0115166Y0873958
X0115166Y0783604
X0099024Y0860572
X0099024Y0853879
X0115166Y0857226
X0115166Y0850533
X0099024Y0847186
X0099024Y0840493
X0115166Y0843840
X0115166Y0837147
X0099024Y0823761
X0099024Y0817068
X0115166Y0776911
X0099024Y0971005
X0115166Y0967659
X0099024Y0957619
X0099024Y0950926
X0115166Y0954273
X0115166Y0947580
X0099024Y0934194
X0099024Y0927501
X0115166Y0930848
X0115166Y0924155
X0115166Y0994430
X0099024Y0991084
X0115166Y0987737
X0099024Y0984391
X0115166Y0981045
X0099024Y0977698
X0115166Y0974352
X0099024Y0964312
X0099024Y0997777
X0099024Y1001123
X1091308Y1064705
X1075166Y1051319
X1091308Y1084784
X1075166Y1238721
R04Y-0036811
X1091308Y1232028
R03Y-0036811
X1091308Y1088130
X1075166Y1235374
R04Y-0036811
X1091308Y1235374
R03Y-0036811
X1091308Y1151713
X1091308Y1145020
X1075166Y1141674
X1075166Y1134981
X1091308Y1138327
X1091308Y1131634
X1075166Y1118248
X1075166Y1252107
X1075166Y1245414
X1075166Y1111555
X1091308Y1248760
X1091308Y1242067
X1075166Y1228681
X1075166Y1221988
X1091308Y1225335
X1091308Y1218642
X1075166Y1215296
X1075166Y1208603
X1091308Y1211949
X1091308Y1205256
X1091308Y1114902
X1075166Y1191870
X1075166Y1185177
X1091308Y1188524
X1091308Y1181831
X1075166Y1178485
X1075166Y1171792
X1091308Y1175138
X1091308Y1168445
X1075166Y1155059
X1075166Y1148366
X1091308Y1108209
X1075166Y1058012
X1091308Y1054666
X1075166Y1081437
X1075166Y1074744
X1091308Y1078091
X1091308Y1071398
X1075166Y1104862
X1075166Y1098170
X1091308Y1101516
X1091308Y1094823
X1091308Y1047973
X1075166Y1044626
X1091308Y1041280
X1075166Y1037933
X1091308Y1034587
X1075166Y1031240
X1091308Y1027894
X1091308Y1061359
X1091308Y1001122
X1075166Y0944233
X1075166Y0907422
X1075166Y0870610
R02Y-0036811
X1091308Y0937540
R04Y-0036811
X1075166Y0940886
R04Y-0036811
X1091308Y0940886
R04Y-0036811
X1091308Y0820414
X1091308Y0813721
X1075166Y0810374
X1075166Y0803681
X1091308Y0807028
X1091308Y0800335
X1075166Y0786949
X1075166Y0920807
X1075166Y0914114
X1075166Y0780256
X1091308Y0917461
X1091308Y0910768
X1075166Y0897382
X1075166Y0890689
X1091308Y0894036
X1091308Y0887343
X1075166Y0883996
X1075166Y0877303
X1091308Y0880650
X1091308Y0873957
X1091308Y0783603
X1075166Y0860571
X1075166Y0853878
X1091308Y0857225
X1091308Y0850532
X1075166Y0847185
X1075166Y0840492
X1091308Y0843839
X1091308Y0837146
X1075166Y0823760
X1075166Y0817067
X1091308Y0776910
X1075166Y0971004
X1091308Y0967658
X1075166Y0957618
X1075166Y0950925
X1091308Y0954272
X1091308Y0947579
X1075166Y0934193
X1075166Y0927500
X1091308Y0930847
X1091308Y0924154
X1091308Y0994429
X1075166Y0991083
X1091308Y0987736
X1075166Y0984390
X1091308Y0981044
X1075166Y0977697
X1091308Y0974351
X1075166Y0964311
X1075166Y0997776
X1075166Y1001122
X0050880Y1418963
X0058349Y1409731
X0050880Y1415563
X0058349Y1406331
M30
